(kicad_pcb
	(version 20260206)
	(generator "pcbnew")
	(generator_version "10.0")
	(general
		(thickness 1.6)
		(legacy_teardrops no)
	)
	(paper "A4")
	(title_block
		(title "Bryce Canyon_IOM_IOC_16318-2_OCP.brd")
		(comment 1 "Bryce Canyon / footprints 1272-1281 of 1605")
	)
	(layers
		(0 "F.Cu" signal "TOP")
		(4 "In1.Cu" signal "L2GND")
		(6 "In2.Cu" signal "L3")
		(8 "In3.Cu" signal "L4VCC")
		(10 "In4.Cu" signal "L5VCC")
		(12 "In5.Cu" signal "L6")
		(14 "In6.Cu" signal "L7GND")
		(2 "B.Cu" signal "BOTTOM")
		(9 "F.Adhes" user "F.Adhesive")
		(11 "B.Adhes" user "B.Adhesive")
		(13 "F.Paste" user "Package Geometry/Pastemask Top")
		(15 "B.Paste" user "Package Geometry/Pastemask Bottom")
		(5 "F.SilkS" user "Ref Des/Silkscreen Top")
		(7 "B.SilkS" user "Ref Des/Silkscreen Bottom")
		(1 "F.Mask" user "Board Geometry/Soldermask Top")
		(3 "B.Mask" user "Board Geometry/Soldermask Bottom")
		(17 "Dwgs.User" user "User.Drawings")
		(19 "Cmts.User" user "User.Comments")
		(21 "Eco1.User" user "User.Eco1")
		(23 "Eco2.User" user "User.Eco2")
		(25 "Edge.Cuts" user "Board Geometry/Outline")
		(27 "Margin" user)
		(31 "F.CrtYd" user "Package Geometry/Place Bound Top")
		(29 "B.CrtYd" user "Package Geometry/Place Bound Bottom")
		(35 "F.Fab" user "Ref Des/Assembly Top")
		(33 "B.Fab" user "Ref Des/Assembly Bottom")
	)
	(footprint ""
		(layer "B.Cu")
		(at 200.359518 -81.153 180)
		(property "Reference" "C291"
			(at 0 0 0)
			(layer "B.SilkS")
			(hide yes)
			(effects
				(font
					(size 1.27 1.27)
				)
				(justify mirror)
			)
		)
		(property "Value" "SCD22U10V1KX-GP"
			(at 2.8321 -1.7399 180)
			(unlocked yes)
			(layer "B.Fab")
			(hide yes)
			(effects
				(font
					(size 1.016 1.016)
					(thickness 0.1524)
				)
				(justify mirror)
			)
		)
		(property "Device Type" "C0201H13"
			(at 2.8321 -3.2639 180)
			(unlocked yes)
			(layer "B.Fab")
			(hide yes)
			(effects
				(font
					(size 1.016 1.016)
					(thickness 0.1524)
				)
				(justify mirror)
			)
		)
		(duplicate_pad_numbers_are_jumpers no)
		(fp_rect
			(start 0.2794 0.6477)
			(end -0.2794 -0.6477)
			(stroke
				(width 0)
				(type default)
			)
			(fill no)
			(layer "B.CrtYd")
		)
		(fp_rect
			(start 0.2794 0.6477)
			(end -0.2794 -0.6477)
			(stroke
				(width 0)
				(type default)
			)
			(fill no)
			(layer "B.Fab")
		)
		(pad "1" smd custom
			(at 0 -0.2794)
			(size 0.0762 0.0762)
			(layers "B.Cu" "B.Mask" "B.Paste")
			(net "PCIE_IOM_TO_COMP_9_DP_C")
			(options
				(clearance outline)
				(anchor circle)
			)
			(primitives
				(gr_poly
					(pts
						(arc
							(start 0.1524 0.127)
							(mid 0.137521 0.162921)
							(end 0.1016 0.1778)
						)
						(arc
							(start -0.1016 0.1778)
							(mid -0.137521 0.162921)
							(end -0.1524 0.127)
						)
						(arc
							(start -0.1524 -0.127)
							(mid -0.137521 -0.162921)
							(end -0.1016 -0.1778)
						)
						(arc
							(start 0.1016 -0.1778)
							(mid 0.137521 -0.162921)
							(end 0.1524 -0.127)
						)
					)
					(width 0)
					(fill yes)
				)
			)
		)
		(pad "2" smd custom
			(at 0 0.2794)
			(size 0.0762 0.0762)
			(layers "B.Cu" "B.Mask" "B.Paste")
			(net "PCIE_IOM_TO_COMP_9_DP")
			(options
				(clearance outline)
				(anchor circle)
			)
			(primitives
				(gr_poly
					(pts
						(arc
							(start 0.1524 0.127)
							(mid 0.137521 0.162921)
							(end 0.1016 0.1778)
						)
						(arc
							(start -0.1016 0.1778)
							(mid -0.137521 0.162921)
							(end -0.1524 0.127)
						)
						(arc
							(start -0.1524 -0.127)
							(mid -0.137521 -0.162921)
							(end -0.1016 -0.1778)
						)
						(arc
							(start 0.1016 -0.1778)
							(mid 0.137521 -0.162921)
							(end 0.1524 -0.127)
						)
					)
					(width 0)
					(fill yes)
				)
			)
		)
	)
	(footprint ""
		(layer "B.Cu")
		(at 207.18018 -61.69406)
		(property "Reference" "TP111"
			(at 0 0 0)
			(layer "B.SilkS")
			(hide yes)
			(effects
				(font
					(size 1.27 1.27)
				)
				(justify mirror)
			)
		)
		(property "Value" "TPAD28-2-GP"
			(at 0.0127 -1.6637 0)
			(unlocked yes)
			(layer "B.Fab")
			(hide yes)
			(effects
				(font
					(size 1.016 1.016)
					(thickness 0.1524)
				)
				(justify mirror)
			)
		)
		(property "Device Type" "TPAD28"
			(at 0.0127 -3.1877 0)
			(unlocked yes)
			(layer "B.Fab")
			(hide yes)
			(effects
				(font
					(size 1.016 1.016)
					(thickness 0.1524)
				)
				(justify mirror)
			)
		)
		(duplicate_pad_numbers_are_jumpers no)
		(fp_poly
			(pts
				(arc
					(start 0.3556 0)
					(mid -0.3556 0)
					(end 0.3556 0)
				)
			)
			(stroke
				(width 0)
				(type default)
			)
			(fill no)
			(layer "B.CrtYd")
		)
		(fp_poly
			(pts
				(arc
					(start 0.6096 0)
					(mid -0.6096 0)
					(end 0.6096 0)
				)
			)
			(stroke
				(width 0)
				(type default)
			)
			(fill no)
			(layer "B.Fab")
		)
		(pad "1" smd circle
			(at 0 0 180)
			(size 0.7112 0.7112)
			(layers "B.Cu" "B.Mask" "B.Paste")
			(net "SIO_CLK_0")
		)
	)
	(footprint ""
		(layer "B.Cu")
		(at 199.800718 -81.153 180)
		(property "Reference" "C292"
			(at 0 0 0)
			(layer "B.SilkS")
			(hide yes)
			(effects
				(font
					(size 1.27 1.27)
				)
				(justify mirror)
			)
		)
		(property "Value" "SCD22U10V1KX-GP"
			(at 2.8321 -1.7399 180)
			(unlocked yes)
			(layer "B.Fab")
			(hide yes)
			(effects
				(font
					(size 1.016 1.016)
					(thickness 0.1524)
				)
				(justify mirror)
			)
		)
		(property "Device Type" "C0201H13"
			(at 2.8321 -3.2639 180)
			(unlocked yes)
			(layer "B.Fab")
			(hide yes)
			(effects
				(font
					(size 1.016 1.016)
					(thickness 0.1524)
				)
				(justify mirror)
			)
		)
		(duplicate_pad_numbers_are_jumpers no)
		(fp_rect
			(start 0.2794 0.6477)
			(end -0.2794 -0.6477)
			(stroke
				(width 0)
				(type default)
			)
			(fill no)
			(layer "B.CrtYd")
		)
		(fp_rect
			(start 0.2794 0.6477)
			(end -0.2794 -0.6477)
			(stroke
				(width 0)
				(type default)
			)
			(fill no)
			(layer "B.Fab")
		)
		(pad "1" smd custom
			(at 0 -0.2794)
			(size 0.0762 0.0762)
			(layers "B.Cu" "B.Mask" "B.Paste")
			(net "PCIE_IOM_TO_COMP_9_DN_C")
			(options
				(clearance outline)
				(anchor circle)
			)
			(primitives
				(gr_poly
					(pts
						(arc
							(start 0.1524 0.127)
							(mid 0.137521 0.162921)
							(end 0.1016 0.1778)
						)
						(arc
							(start -0.1016 0.1778)
							(mid -0.137521 0.162921)
							(end -0.1524 0.127)
						)
						(arc
							(start -0.1524 -0.127)
							(mid -0.137521 -0.162921)
							(end -0.1016 -0.1778)
						)
						(arc
							(start 0.1016 -0.1778)
							(mid 0.137521 -0.162921)
							(end 0.1524 -0.127)
						)
					)
					(width 0)
					(fill yes)
				)
			)
		)
		(pad "2" smd custom
			(at 0 0.2794)
			(size 0.0762 0.0762)
			(layers "B.Cu" "B.Mask" "B.Paste")
			(net "PCIE_IOM_TO_COMP_9_DN")
			(options
				(clearance outline)
				(anchor circle)
			)
			(primitives
				(gr_poly
					(pts
						(arc
							(start 0.1524 0.127)
							(mid 0.137521 0.162921)
							(end 0.1016 0.1778)
						)
						(arc
							(start -0.1016 0.1778)
							(mid -0.137521 0.162921)
							(end -0.1524 0.127)
						)
						(arc
							(start -0.1524 -0.127)
							(mid -0.137521 -0.162921)
							(end -0.1016 -0.1778)
						)
						(arc
							(start 0.1016 -0.1778)
							(mid 0.137521 -0.162921)
							(end 0.1524 -0.127)
						)
					)
					(width 0)
					(fill yes)
				)
			)
		)
	)
	(footprint ""
		(layer "B.Cu")
		(at 175.133 -77.978 180)
		(property "Reference" "C345"
			(at 0 0 0)
			(layer "B.SilkS")
			(hide yes)
			(effects
				(font
					(size 1.27 1.27)
				)
				(justify mirror)
			)
		)
		(property "Value" "SCD1U6D3V1KX-GP"
			(at 2.8321 -1.7399 180)
			(unlocked yes)
			(layer "B.Fab")
			(hide yes)
			(effects
				(font
					(size 1.016 1.016)
					(thickness 0.1524)
				)
				(justify mirror)
			)
		)
		(property "Device Type" "C0201H13"
			(at 2.8321 -3.2639 180)
			(unlocked yes)
			(layer "B.Fab")
			(hide yes)
			(effects
				(font
					(size 1.016 1.016)
					(thickness 0.1524)
				)
				(justify mirror)
			)
		)
		(duplicate_pad_numbers_are_jumpers no)
		(fp_rect
			(start 0.2794 0.6477)
			(end -0.2794 -0.6477)
			(stroke
				(width 0)
				(type default)
			)
			(fill no)
			(layer "B.CrtYd")
		)
		(fp_rect
			(start 0.2794 0.6477)
			(end -0.2794 -0.6477)
			(stroke
				(width 0)
				(type default)
			)
			(fill no)
			(layer "B.Fab")
		)
		(pad "1" smd custom
			(at 0 -0.2794)
			(size 0.0762 0.0762)
			(layers "B.Cu" "B.Mask" "B.Paste")
			(net "PLL_VDD")
			(options
				(clearance outline)
				(anchor circle)
			)
			(primitives
				(gr_poly
					(pts
						(arc
							(start 0.1524 0.127)
							(mid 0.137521 0.162921)
							(end 0.1016 0.1778)
						)
						(arc
							(start -0.1016 0.1778)
							(mid -0.137521 0.162921)
							(end -0.1524 0.127)
						)
						(arc
							(start -0.1524 -0.127)
							(mid -0.137521 -0.162921)
							(end -0.1016 -0.1778)
						)
						(arc
							(start 0.1016 -0.1778)
							(mid 0.137521 -0.162921)
							(end 0.1524 -0.127)
						)
					)
					(width 0)
					(fill yes)
				)
			)
		)
		(pad "2" smd custom
			(at 0 0.2794)
			(size 0.0762 0.0762)
			(layers "B.Cu" "B.Mask" "B.Paste")
			(net "GND")
			(options
				(clearance outline)
				(anchor circle)
			)
			(primitives
				(gr_poly
					(pts
						(arc
							(start 0.1524 0.127)
							(mid 0.137521 0.162921)
							(end 0.1016 0.1778)
						)
						(arc
							(start -0.1016 0.1778)
							(mid -0.137521 0.162921)
							(end -0.1524 0.127)
						)
						(arc
							(start -0.1524 -0.127)
							(mid -0.137521 -0.162921)
							(end -0.1016 -0.1778)
						)
						(arc
							(start 0.1016 -0.1778)
							(mid 0.137521 -0.162921)
							(end 0.1524 -0.127)
						)
					)
					(width 0)
					(fill yes)
				)
			)
		)
	)
	(footprint ""
		(layer "B.Cu")
		(at 93.3704 -178.7398 180)
		(property "Reference" "C39"
			(at 0 0 0)
			(layer "B.SilkS")
			(hide yes)
			(effects
				(font
					(size 1.27 1.27)
				)
				(justify mirror)
			)
		)
		(property "Value" "SCD1U16V2KX-3GP"
			(at -1.1811 -2.7051 180)
			(unlocked yes)
			(layer "B.Fab")
			(hide yes)
			(effects
				(font
					(size 1.016 1.016)
					(thickness 0.1524)
				)
				(justify mirror)
			)
		)
		(property "Device Type" "C402H22"
			(at -1.1811 -4.2291 180)
			(unlocked yes)
			(layer "B.Fab")
			(hide yes)
			(effects
				(font
					(size 1.016 1.016)
					(thickness 0.1524)
				)
				(justify mirror)
			)
		)
		(duplicate_pad_numbers_are_jumpers no)
		(fp_rect
			(start 0.4318 0.9525)
			(end -0.4318 -0.9525)
			(stroke
				(width 0)
				(type default)
			)
			(fill no)
			(layer "B.CrtYd")
		)
		(fp_rect
			(start 0.4318 0.9525)
			(end -0.4318 -0.9525)
			(stroke
				(width 0)
				(type default)
			)
			(fill no)
			(layer "B.Fab")
		)
		(pad "1" smd custom
			(at 0 -0.4445)
			(size 0.1524 0.1524)
			(layers "B.Cu" "B.Mask" "B.Paste")
			(net "P3V3_STBY")
			(options
				(clearance outline)
				(anchor circle)
			)
			(primitives
				(gr_poly
					(pts
						(arc
							(start 0.3048 0.2032)
							(mid 0.275042 0.275042)
							(end 0.2032 0.3048)
						)
						(arc
							(start -0.2032 0.3048)
							(mid -0.275042 0.275042)
							(end -0.3048 0.2032)
						)
						(arc
							(start -0.3048 -0.2032)
							(mid -0.275042 -0.275042)
							(end -0.2032 -0.3048)
						)
						(arc
							(start 0.2032 -0.3048)
							(mid 0.275042 -0.275042)
							(end 0.3048 -0.2032)
						)
					)
					(width 0)
					(fill yes)
				)
			)
		)
		(pad "2" smd custom
			(at 0 0.4445)
			(size 0.1524 0.1524)
			(layers "B.Cu" "B.Mask" "B.Paste")
			(net "GND")
			(options
				(clearance outline)
				(anchor circle)
			)
			(primitives
				(gr_poly
					(pts
						(arc
							(start 0.3048 0.2032)
							(mid 0.275042 0.275042)
							(end 0.2032 0.3048)
						)
						(arc
							(start -0.2032 0.3048)
							(mid -0.275042 0.275042)
							(end -0.3048 0.2032)
						)
						(arc
							(start -0.3048 -0.2032)
							(mid -0.275042 -0.275042)
							(end -0.2032 -0.3048)
						)
						(arc
							(start 0.2032 -0.3048)
							(mid 0.275042 -0.275042)
							(end 0.3048 -0.2032)
						)
					)
					(width 0)
					(fill yes)
				)
			)
		)
	)
	(footprint ""
		(layer "B.Cu")
		(at 204.815948 -47.773082 -90)
		(property "Reference" "L15"
			(at 0 0 90)
			(layer "B.SilkS")
			(hide yes)
			(effects
				(font
					(size 1.27 1.27)
				)
				(justify mirror)
			)
		)
		(property "Value" "MPZ2012S601AT-GP"
			(at 0 -4.2418 270)
			(unlocked yes)
			(layer "B.Fab")
			(hide yes)
			(effects
				(font
					(size 1.016 1.016)
					(thickness 0.1524)
				)
				(justify mirror)
			)
		)
		(property "Device Type" "L805H42"
			(at 0 -5.7912 270)
			(unlocked yes)
			(layer "B.Fab")
			(hide yes)
			(effects
				(font
					(size 1.016 1.016)
					(thickness 0.1524)
				)
				(justify mirror)
			)
		)
		(duplicate_pad_numbers_are_jumpers no)
		(fp_line
			(start -0.889 1.7018)
			(end 0.889 1.7018)
			(stroke
				(width 0.1524)
				(type default)
			)
			(layer "B.SilkS")
		)
		(fp_line
			(start 0.889 1.7018)
			(end 0.889 -1.7018)
			(stroke
				(width 0.1524)
				(type default)
			)
			(layer "B.SilkS")
		)
		(fp_line
			(start -0.889 -1.7018)
			(end -0.889 1.7018)
			(stroke
				(width 0.1524)
				(type default)
			)
			(layer "B.SilkS")
		)
		(fp_line
			(start 0.889 -1.7018)
			(end -0.889 -1.7018)
			(stroke
				(width 0.1524)
				(type default)
			)
			(layer "B.SilkS")
		)
		(fp_rect
			(start 0.9652 1.778)
			(end -0.9652 -1.778)
			(stroke
				(width 0)
				(type default)
			)
			(fill no)
			(layer "B.CrtYd")
		)
		(fp_rect
			(start 0.9652 1.778)
			(end -0.9652 -1.778)
			(stroke
				(width 0)
				(type default)
			)
			(fill no)
			(layer "B.Fab")
		)
		(pad "1" smd rect
			(at 0 -0.9652 90)
			(size 1.397 1.143)
			(layers "B.Cu" "B.Mask" "B.Paste")
			(net "SHELL_PLL_VDD")
		)
		(pad "2" smd rect
			(at 0 0.9652 90)
			(size 1.397 1.143)
			(layers "B.Cu" "B.Mask" "B.Paste")
			(net "P1V8")
		)
	)
	(footprint ""
		(layer "B.Cu")
		(at 52.5526 -146.5834 -90)
		(property "Reference" "TP51"
			(at 0 0 90)
			(layer "B.SilkS")
			(hide yes)
			(effects
				(font
					(size 1.27 1.27)
				)
				(justify mirror)
			)
		)
		(property "Value" "TPAD28-2-GP"
			(at 0.0127 -1.6637 270)
			(unlocked yes)
			(layer "B.Fab")
			(hide yes)
			(effects
				(font
					(size 1.016 1.016)
					(thickness 0.1524)
				)
				(justify mirror)
			)
		)
		(property "Device Type" "TPAD28"
			(at 0.0127 -3.1877 270)
			(unlocked yes)
			(layer "B.Fab")
			(hide yes)
			(effects
				(font
					(size 1.016 1.016)
					(thickness 0.1524)
				)
				(justify mirror)
			)
		)
		(duplicate_pad_numbers_are_jumpers no)
		(fp_poly
			(pts
				(arc
					(start 0 -0.3556)
					(mid 0 0.3556)
					(end 0 -0.3556)
				)
			)
			(stroke
				(width 0)
				(type default)
			)
			(fill no)
			(layer "B.CrtYd")
		)
		(fp_poly
			(pts
				(arc
					(start 0 -0.6096)
					(mid 0 0.6096)
					(end 0 -0.6096)
				)
			)
			(stroke
				(width 0)
				(type default)
			)
			(fill no)
			(layer "B.Fab")
		)
		(pad "1" smd circle
			(at 0 0 90)
			(size 0.7112 0.7112)
			(layers "B.Cu" "B.Mask" "B.Paste")
			(net "RMII_BMC_MDC_R")
		)
	)
	(footprint ""
		(layer "B.Cu")
		(at 195.5927 -63.78956 90)
		(property "Reference" "C422"
			(at 0 0 90)
			(layer "B.SilkS")
			(hide yes)
			(effects
				(font
					(size 1.27 1.27)
				)
				(justify mirror)
			)
		)
		(property "Value" "SCD1U6D3V1KX-GP"
			(at 2.8321 -1.7399 90)
			(unlocked yes)
			(layer "B.Fab")
			(hide yes)
			(effects
				(font
					(size 1.016 1.016)
					(thickness 0.1524)
				)
				(justify mirror)
			)
		)
		(property "Device Type" "C0201H13"
			(at 2.8321 -3.2639 90)
			(unlocked yes)
			(layer "B.Fab")
			(hide yes)
			(effects
				(font
					(size 1.016 1.016)
					(thickness 0.1524)
				)
				(justify mirror)
			)
		)
		(duplicate_pad_numbers_are_jumpers no)
		(fp_rect
			(start 0.2794 0.6477)
			(end -0.2794 -0.6477)
			(stroke
				(width 0)
				(type default)
			)
			(fill no)
			(layer "B.CrtYd")
		)
		(fp_rect
			(start 0.2794 0.6477)
			(end -0.2794 -0.6477)
			(stroke
				(width 0)
				(type default)
			)
			(fill no)
			(layer "B.Fab")
		)
		(pad "1" smd custom
			(at 0 -0.2794 270)
			(size 0.0762 0.0762)
			(layers "B.Cu" "B.Mask" "B.Paste")
			(net "P0V975")
			(options
				(clearance outline)
				(anchor circle)
			)
			(primitives
				(gr_poly
					(pts
						(arc
							(start 0.1524 0.127)
							(mid 0.137521 0.162921)
							(end 0.1016 0.1778)
						)
						(arc
							(start -0.1016 0.1778)
							(mid -0.137521 0.162921)
							(end -0.1524 0.127)
						)
						(arc
							(start -0.1524 -0.127)
							(mid -0.137521 -0.162921)
							(end -0.1016 -0.1778)
						)
						(arc
							(start 0.1016 -0.1778)
							(mid 0.137521 -0.162921)
							(end 0.1524 -0.127)
						)
					)
					(width 0)
					(fill yes)
				)
			)
		)
		(pad "2" smd custom
			(at 0 0.2794 270)
			(size 0.0762 0.0762)
			(layers "B.Cu" "B.Mask" "B.Paste")
			(net "GND")
			(options
				(clearance outline)
				(anchor circle)
			)
			(primitives
				(gr_poly
					(pts
						(arc
							(start 0.1524 0.127)
							(mid 0.137521 0.162921)
							(end 0.1016 0.1778)
						)
						(arc
							(start -0.1016 0.1778)
							(mid -0.137521 0.162921)
							(end -0.1524 0.127)
						)
						(arc
							(start -0.1524 -0.127)
							(mid -0.137521 -0.162921)
							(end -0.1016 -0.1778)
						)
						(arc
							(start 0.1016 -0.1778)
							(mid 0.137521 -0.162921)
							(end 0.1524 -0.127)
						)
					)
					(width 0)
					(fill yes)
				)
			)
		)
	)
	(footprint ""
		(layer "B.Cu")
		(at 200.94956 -62.92596)
		(property "Reference" "TP134"
			(at 0 0 0)
			(layer "B.SilkS")
			(hide yes)
			(effects
				(font
					(size 1.27 1.27)
				)
				(justify mirror)
			)
		)
		(property "Value" "TPAD28-2-GP"
			(at 0.0127 -1.6637 0)
			(unlocked yes)
			(layer "B.Fab")
			(hide yes)
			(effects
				(font
					(size 1.016 1.016)
					(thickness 0.1524)
				)
				(justify mirror)
			)
		)
		(property "Device Type" "TPAD28"
			(at 0.0127 -3.1877 0)
			(unlocked yes)
			(layer "B.Fab")
			(hide yes)
			(effects
				(font
					(size 1.016 1.016)
					(thickness 0.1524)
				)
				(justify mirror)
			)
		)
		(duplicate_pad_numbers_are_jumpers no)
		(fp_poly
			(pts
				(arc
					(start 0.3556 0)
					(mid -0.3556 0)
					(end 0.3556 0)
				)
			)
			(stroke
				(width 0)
				(type default)
			)
			(fill no)
			(layer "B.CrtYd")
		)
		(fp_poly
			(pts
				(arc
					(start 0.6096 0)
					(mid -0.6096 0)
					(end 0.6096 0)
				)
			)
			(stroke
				(width 0)
				(type default)
			)
			(fill no)
			(layer "B.Fab")
		)
		(pad "1" smd circle
			(at 0 0 180)
			(size 0.7112 0.7112)
			(layers "B.Cu" "B.Mask" "B.Paste")
			(net "ICE_SEL")
		)
	)
	(footprint ""
		(layer "B.Cu")
		(at 192.405 -48.641 -90)
		(property "Reference" "C332"
			(at 0 0 90)
			(layer "B.SilkS")
			(hide yes)
			(effects
				(font
					(size 1.27 1.27)
				)
				(justify mirror)
			)
		)
		(property "Value" "SC10U6D3V5KX-4GP"
			(at 0.0762 -6.1214 270)
			(unlocked yes)
			(layer "B.Fab")
			(hide yes)
			(effects
				(font
					(size 1.016 1.016)
					(thickness 0.1524)
				)
				(justify mirror)
			)
		)
		(property "Device Type" "C805H58"
			(at 0.0762 -8.1534 270)
			(unlocked yes)
			(layer "B.Fab")
			(hide yes)
			(effects
				(font
					(size 1.016 1.016)
					(thickness 0.1524)
				)
				(justify mirror)
			)
		)
		(duplicate_pad_numbers_are_jumpers no)
		(fp_line
			(start -0.635 0)
			(end 0.635 0)
			(stroke
				(width 0.508)
				(type default)
			)
			(layer "B.SilkS")
		)
		(fp_rect
			(start 0.9652 1.778)
			(end -0.9652 -1.778)
			(stroke
				(width 0)
				(type default)
			)
			(fill no)
			(layer "B.CrtYd")
		)
		(fp_poly
			(pts
				(xy 0.9652 -1.778) (xy -0.9652 -1.778) (xy -0.9652 1.778) (xy 0.9652 1.778)
			)
			(stroke
				(width 0)
				(type default)
			)
			(fill no)
			(layer "B.Fab")
		)
		(pad "1" smd rect
			(at 0 -0.9652 90)
			(size 1.397 1.143)
			(layers "B.Cu" "B.Mask" "B.Paste")
			(net "HM40ADC_VDDA")
		)
		(pad "2" smd rect
			(at 0 0.9652 90)
			(size 1.397 1.143)
			(layers "B.Cu" "B.Mask" "B.Paste")
			(net "GND")
		)
	)
)
